FILE_TYPE = MULTI_PHYS_TABLE;

PART '74LVC1G66GV'

{========================================================================================}
:VALUE         | PART_TYPE | MATERIAL | PART_NUMBER       = STANDARD | LIFECYCLE      | PART_NUMBER       | JEDEC_TYPE | DESCRIPTION                        | MANUFTR | MANUF_PN      | RD_CMPLS_LVL | CMPLS_LVL | FROM_PJ       | CLASS | DIP_SMD | DATA                | EE_CHECK_LIST | FP_ECN           | PSL | CREATOR | STATUS | CREATEDAY  ;
{========================================================================================}
 '74LVC1G66GV' | 'SMLF'    | 'IC'     | 'AL001G66000'(!)  = ''       | ''             | 'AL001G66000'     |'SC74AXA'| 'IC(5P) 74LVC1G66GV(SOT753)'       | 'PHI'   | '74LVC1G66GV' | ''           | 'EP'      | 'S4P-FRANK'   | 'IC'  | ''      | 'PHI_74LVC1G66.pdf' | 'SC74AXA.xls' | ''               | ''  | ''      | ''     | '20140912'
 '74LVC1G66GV' | 'SMLF'    | 'EMPTY'  | 'AL001G66000'(!)  = ''       | ''             | 'AL001G66000'     |'SC74AXA'| 'IC(5P) 74LVC1G66GV(SOT753)'       | 'PHI'   | '74LVC1G66GV' | ''           | 'EP'      | 'S4P-FRANK'   | 'IC'  | ''      | 'PHI_74LVC1G66.pdf' | 'SC74AXA.xls' | ''               | ''  | ''      | ''     | '20140912'
 '74LVC1G66GV' | 'SMLF'    | 'IC'     | 'AL001G66000SEL1'(!) = ''       | ''               | 'AL001G66000SEL1' |'SC74AXA'| 'IC(5P) 74LVC1G66GV(SOT753)SELASN' | 'PHI'   | '74LVC1G66GV' | ''           | 'EP'      | 'S2E-CHAOWEN' | 'IC'  | ''      | 'PHI_74LVC1G66.pdf' | ''            | 'SEL_15QPN.xlsx' | ''  | ''      | ''     | '20230719'
 '74LVC1G66GV' | 'SMLF'    | 'EMPTY'  | 'AL001G66000SEL1'(!) = ''       | ''               | 'AL001G66000SEL1' |'SC74AXA'| 'IC(5P) 74LVC1G66GV(SOT753)SELASN' | 'PHI'   | '74LVC1G66GV' | ''           | 'EP'      | 'S2E-CHAOWEN' | 'IC'  | ''      | 'PHI_74LVC1G66.pdf' | ''            | 'SEL_15QPN.xlsx' | ''  | ''      | ''     | '20230719'

END_PART

END.

